# S9S_MB_2U (Grand Teton) — schematic netlist excerpt (pin names and nets, part order shuffled) for the footprints in the layout excerpt that follows; sources: Cadence DE-HDL packaged netlist, KiCad conversion of 03242023_DA0F0TMBIJ0_F0T_Motherboard_J_brd_V01_OCP.brd

U22  NC7SB3157  NC7SB3157P6X IC  pkg SMLF  page 133
  B1  = JTAG_CPU0_MUX_GTL_TDO
  GND  = GND
  B0  = JTAG_CPU1_MUX_GTL_TDO
  A  = JTAG_MUX_QS_GTL_TDO
  VCC  = P3V3_AUX
  S  = FM_CPU1_SKTOCC_N

C91  Q_CAP  10UF 16V 10% X6S  pkg C0805  page 107 : A = P12V_S3_AUX_CPU1_NVDIMM ; B = GND

(kicad_pcb
	(version 20260206)
	(generator "pcbnew")
	(generator_version "10.0")
	(general
		(thickness 1.6)
		(legacy_teardrops no)
	)
	(paper "A4")
	(title_block
		(title "03242023_DA0F0TMBIJ0_F0T_Motherboard_J_brd_V01_OCP.brd")
		(comment 1 "Grand Teton / footprints 5599-5600 of 6105")
	)
	(layers
		(0 "F.Cu" signal "TOP")
		(4 "In1.Cu" signal "GND")
		(6 "In2.Cu" signal "IN1")
		(8 "In3.Cu" signal "GND1")
		(10 "In4.Cu" signal "IN2")
		(12 "In5.Cu" signal "GND2")
		(14 "In6.Cu" signal "IN3")
		(16 "In7.Cu" signal "GND3")
		(18 "In8.Cu" signal "VCC")
		(20 "In9.Cu" signal "VCC1")
		(22 "In10.Cu" signal "GND4")
		(24 "In11.Cu" signal "IN4")
		(26 "In12.Cu" signal "GND5")
		(28 "In13.Cu" signal "IN5")
		(30 "In14.Cu" signal "GND6")
		(32 "In15.Cu" signal "IN6")
		(34 "In16.Cu" signal "GND7")
		(2 "B.Cu" signal "BOTTOM")
		(9 "F.Adhes" user "F.Adhesive")
		(11 "B.Adhes" user "B.Adhesive")
		(13 "F.Paste" user "Package Geometry/Pastemask Top")
		(15 "B.Paste" user "Package Geometry/Pastemask Bottom")
		(5 "F.SilkS" user "Ref Des/Silkscreen Top")
		(7 "B.SilkS" user "Ref Des/Silkscreen Bottom")
		(1 "F.Mask" user "Board Geometry/Soldermask Top")
		(3 "B.Mask" user "Board Geometry/Soldermask Bottom")
		(17 "Dwgs.User" user "User.Drawings")
		(19 "Cmts.User" user "User.Comments")
		(21 "Eco1.User" user "User.Eco1")
		(23 "Eco2.User" user "User.Eco2")
		(25 "Edge.Cuts" user "Board Geometry/Outline")
		(27 "Margin" user)
		(31 "F.CrtYd" user "Package Geometry/Place Bound Top")
		(29 "B.CrtYd" user "Package Geometry/Place Bound Bottom")
		(35 "F.Fab" user "Ref Des/Assembly Top")
		(33 "B.Fab" user "Ref Des/Assembly Bottom")
	)
	(footprint ""
		(layer "B.Cu")
		(at 212.612478 -193.42989)
		(property "Reference" "U22"
			(at 0.09398 2.04089 0)
			(unlocked yes)
			(layer "B.SilkS")
			(effects
				(font
					(size 0.7874 0.5842)
					(thickness 0.1524)
				)
				(justify mirror)
			)
		)
		(property "Value" ""
			(at 0 0 0)
			(layer "B.Fab")
			(effects
				(font
					(size 1.27 1.27)
				)
				(justify mirror)
			)
		)
		(duplicate_pad_numbers_are_jumpers no)
		(fp_line
			(start -1.7272 -1.1176)
			(end -1.7272 1.1176)
			(stroke
				(width 0.1524)
				(type default)
			)
			(layer "B.SilkS")
		)
		(fp_line
			(start -1.7272 -1.1176)
			(end -0.254 -1.1176)
			(stroke
				(width 0.1524)
				(type default)
			)
			(layer "B.SilkS")
		)
		(fp_line
			(start -1.7272 1.1176)
			(end 1.7272 1.1176)
			(stroke
				(width 0.1524)
				(type default)
			)
			(layer "B.SilkS")
		)
		(fp_line
			(start -0.254 -1.1176)
			(end 0 -0.7366)
			(stroke
				(width 0.1524)
				(type default)
			)
			(layer "B.SilkS")
		)
		(fp_line
			(start 0 -0.7366)
			(end 0.254 -1.1176)
			(stroke
				(width 0.1524)
				(type default)
			)
			(layer "B.SilkS")
		)
		(fp_line
			(start 0.254 -1.1176)
			(end 1.7272 -1.1176)
			(stroke
				(width 0.1524)
				(type default)
			)
			(layer "B.SilkS")
		)
		(fp_line
			(start 1.7272 1.1176)
			(end 1.7272 -1.1176)
			(stroke
				(width 0.1524)
				(type default)
			)
			(layer "B.SilkS")
		)
		(fp_poly
			(pts
				(xy 1.86436 -0.898906) (xy 2.177542 -1.05537) (xy 2.177542 -0.742442)
			)
			(stroke
				(width 0)
				(type default)
			)
			(fill yes)
			(layer "B.SilkS")
		)
		(fp_line
			(start -1.5748 -1.1176)
			(end 1.5748 -1.1176)
			(stroke
				(width 0.1)
				(type default)
			)
			(layer "B.Fab")
		)
		(fp_line
			(start -1.5748 1.1176)
			(end -1.5748 -1.1176)
			(stroke
				(width 0.1)
				(type default)
			)
			(layer "B.Fab")
		)
		(fp_line
			(start 1.5748 -1.1176)
			(end 1.5748 1.1176)
			(stroke
				(width 0.1)
				(type default)
			)
			(layer "B.Fab")
		)
		(fp_line
			(start 1.5748 1.1176)
			(end -1.5748 1.1176)
			(stroke
				(width 0.1)
				(type default)
			)
			(layer "B.Fab")
		)
		(fp_poly
			(pts
				(xy 1.9558 -0.649986) (xy 2.7178 -0.268986) (xy 2.7178 -1.030986)
			)
			(stroke
				(width 0)
				(type default)
			)
			(fill yes)
			(layer "B.Fab")
		)
		(pad "1" smd rect
			(at 0.999998 -0.649986 270)
			(size 0.3556 1.1176)
			(layers "B.Cu" "B.Mask" "B.Paste")
			(net "JTAG_CPU0_MUX_GTL_TDO")
		)
		(pad "2" smd rect
			(at 0.999998 0 270)
			(size 0.3556 1.1176)
			(layers "B.Cu" "B.Mask" "B.Paste")
			(net "GND")
		)
		(pad "3" smd rect
			(at 0.999998 0.649986 270)
			(size 0.3556 1.1176)
			(layers "B.Cu" "B.Mask" "B.Paste")
			(net "JTAG_CPU1_MUX_GTL_TDO")
		)
		(pad "4" smd rect
			(at -0.999998 0.649986 270)
			(size 0.3556 1.1176)
			(layers "B.Cu" "B.Mask" "B.Paste")
			(net "JTAG_MUX_QS_GTL_TDO")
		)
		(pad "5" smd rect
			(at -0.999998 0 270)
			(size 0.3556 1.1176)
			(layers "B.Cu" "B.Mask" "B.Paste")
			(net "P3V3_AUX")
		)
		(pad "6" smd rect
			(at -0.999998 -0.649986 270)
			(size 0.3556 1.1176)
			(layers "B.Cu" "B.Mask" "B.Paste")
			(net "FM_CPU1_SKTOCC_N")
		)
	)
	(footprint ""
		(layer "B.Cu")
		(at 158.825946 -321.554856 -90)
		(property "Reference" "C91"
			(at 0 0 90)
			(layer "B.SilkS")
			(hide yes)
			(effects
				(font
					(size 1.27 1.27)
				)
				(justify mirror)
			)
		)
		(property "Value" ""
			(at 0 0 90)
			(layer "B.Fab")
			(effects
				(font
					(size 1.27 1.27)
				)
				(justify mirror)
			)
		)
		(duplicate_pad_numbers_are_jumpers no)
		(fp_line
			(start -1.524 0.762)
			(end 1.524 0.762)
			(stroke
				(width 0.1524)
				(type default)
			)
			(layer "B.SilkS")
		)
		(fp_line
			(start 1.524 0.762)
			(end 1.524 -0.762)
			(stroke
				(width 0.1524)
				(type default)
			)
			(layer "B.SilkS")
		)
		(fp_line
			(start -1.524 -0.762)
			(end -1.524 0.762)
			(stroke
				(width 0.1524)
				(type default)
			)
			(layer "B.SilkS")
		)
		(fp_line
			(start 1.524 -0.762)
			(end -1.524 -0.762)
			(stroke
				(width 0.1524)
				(type default)
			)
			(layer "B.SilkS")
		)
		(fp_line
			(start -1.1049 0.724916)
			(end -1.1049 -0.724916)
			(stroke
				(width 0.1)
				(type default)
			)
			(layer "B.Fab")
		)
		(fp_line
			(start 1.1049 0.724916)
			(end -1.1049 0.724916)
			(stroke
				(width 0.1)
				(type default)
			)
			(layer "B.Fab")
		)
		(fp_line
			(start -1.1049 -0.724916)
			(end 1.1049 -0.724916)
			(stroke
				(width 0.1)
				(type default)
			)
			(layer "B.Fab")
		)
		(fp_line
			(start 1.1049 -0.724916)
			(end 1.1049 0.724916)
			(stroke
				(width 0.1)
				(type default)
			)
			(layer "B.Fab")
		)
		(pad "1" smd rect
			(at 0.889 0 270)
			(size 1.016 1.27)
			(layers "B.Cu" "B.Mask" "B.Paste")
			(net "P12V_S3_AUX_CPU1_NVDIMM")
		)
		(pad "2" smd rect
			(at -0.889 0 270)
			(size 1.016 1.27)
			(layers "B.Cu" "B.Mask" "B.Paste")
			(net "GND")
		)
	)
)
